(kicad_pcb
	(version 20260206)
	(generator "pcbnew")
	(generator_version "10.0")
	(general
		(thickness 1.6)
		(legacy_teardrops no)
	)
	(paper "A4")
	(title_block
		(title "Bryce Canyon_IOM_IOC_16318-2_OCP.brd")
		(comment 1 "Bryce Canyon / footprints 272-279 of 1605")
	)
	(layers
		(0 "F.Cu" signal "TOP")
		(4 "In1.Cu" signal "L2GND")
		(6 "In2.Cu" signal "L3")
		(8 "In3.Cu" signal "L4VCC")
		(10 "In4.Cu" signal "L5VCC")
		(12 "In5.Cu" signal "L6")
		(14 "In6.Cu" signal "L7GND")
		(2 "B.Cu" signal "BOTTOM")
		(9 "F.Adhes" user "F.Adhesive")
		(11 "B.Adhes" user "B.Adhesive")
		(13 "F.Paste" user "Package Geometry/Pastemask Top")
		(15 "B.Paste" user "Package Geometry/Pastemask Bottom")
		(5 "F.SilkS" user "Ref Des/Silkscreen Top")
		(7 "B.SilkS" user "Ref Des/Silkscreen Bottom")
		(1 "F.Mask" user "Board Geometry/Soldermask Top")
		(3 "B.Mask" user "Board Geometry/Soldermask Bottom")
		(17 "Dwgs.User" user "User.Drawings")
		(19 "Cmts.User" user "User.Comments")
		(21 "Eco1.User" user "User.Eco1")
		(23 "Eco2.User" user "User.Eco2")
		(25 "Edge.Cuts" user "Board Geometry/Outline")
		(27 "Margin" user)
		(31 "F.CrtYd" user "Package Geometry/Place Bound Top")
		(29 "B.CrtYd" user "Package Geometry/Place Bound Bottom")
		(35 "F.Fab" user "Ref Des/Assembly Top")
		(33 "B.Fab" user "Ref Des/Assembly Bottom")
	)
	(footprint ""
		(layer "F.Cu")
		(at 180.35524 -82.94624 180)
		(property "Reference" "R656"
			(at 0 0 180)
			(layer "F.SilkS")
			(hide yes)
			(effects
				(font
					(size 1.27 1.27)
				)
			)
		)
		(property "Value" "10KR2F-2-GP"
			(at 0.064008 -3.993896 180)
			(unlocked yes)
			(layer "F.Fab")
			(hide yes)
			(effects
				(font
					(size 1.016 1.016)
					(thickness 0.1524)
				)
			)
		)
		(property "Device Type" "R402H16"
			(at 0.064008 -5.517896 180)
			(unlocked yes)
			(layer "F.Fab")
			(hide yes)
			(effects
				(font
					(size 1.016 1.016)
					(thickness 0.1524)
				)
			)
		)
		(duplicate_pad_numbers_are_jumpers no)
		(fp_line
			(start 0.508 -0.9398)
			(end -0.508 -0.9398)
			(stroke
				(width 0.1524)
				(type default)
			)
			(layer "F.SilkS")
		)
		(fp_line
			(start -0.508 -0.9398)
			(end -0.508 0.9398)
			(stroke
				(width 0.1524)
				(type default)
			)
			(layer "F.SilkS")
		)
		(fp_rect
			(start -0.508 0.9398)
			(end 0.508 -0.9398)
			(stroke
				(width 0)
				(type default)
			)
			(fill no)
			(layer "F.CrtYd")
		)
		(fp_rect
			(start -0.508 0.9398)
			(end 0.508 -0.9398)
			(stroke
				(width 0)
				(type default)
			)
			(fill no)
			(layer "F.Fab")
		)
		(pad "1" smd custom
			(at 0 -0.4445 180)
			(size 0.1397 0.1397)
			(layers "F.Cu" "F.Mask" "F.Paste")
			(net "SYS_DBMODE0")
			(options
				(clearance outline)
				(anchor circle)
			)
			(primitives
				(gr_poly
					(pts
						(arc
							(start -0.1778 -0.2794)
							(mid -0.249642 -0.249642)
							(end -0.2794 -0.1778)
						)
						(arc
							(start -0.2794 0.1778)
							(mid -0.249642 0.249642)
							(end -0.1778 0.2794)
						)
						(arc
							(start 0.1778 0.2794)
							(mid 0.249642 0.249642)
							(end 0.2794 0.1778)
						)
						(arc
							(start 0.2794 -0.1778)
							(mid 0.249642 -0.249642)
							(end 0.1778 -0.2794)
						)
					)
					(width 0)
					(fill yes)
				)
			)
		)
		(pad "2" smd custom
			(at 0 0.4445 180)
			(size 0.1397 0.1397)
			(layers "F.Cu" "F.Mask" "F.Paste")
			(net "GND")
			(options
				(clearance outline)
				(anchor circle)
			)
			(primitives
				(gr_poly
					(pts
						(arc
							(start -0.1778 -0.2794)
							(mid -0.249642 -0.249642)
							(end -0.2794 -0.1778)
						)
						(arc
							(start -0.2794 0.1778)
							(mid -0.249642 0.249642)
							(end -0.1778 0.2794)
						)
						(arc
							(start 0.1778 0.2794)
							(mid 0.249642 0.249642)
							(end 0.2794 0.1778)
						)
						(arc
							(start 0.2794 -0.1778)
							(mid 0.249642 -0.249642)
							(end 0.1778 -0.2794)
						)
					)
					(width 0)
					(fill yes)
				)
			)
		)
	)
	(footprint ""
		(layer "F.Cu")
		(at 98.484182 -151.45766 180)
		(property "Reference" "R43"
			(at 0 0 180)
			(layer "F.SilkS")
			(hide yes)
			(effects
				(font
					(size 1.27 1.27)
				)
			)
		)
		(property "Value" "4K7R2F-GP"
			(at 0.064008 -3.993896 180)
			(unlocked yes)
			(layer "F.Fab")
			(hide yes)
			(effects
				(font
					(size 1.016 1.016)
					(thickness 0.1524)
				)
			)
		)
		(property "Device Type" "R402H16"
			(at 0.064008 -5.517896 180)
			(unlocked yes)
			(layer "F.Fab")
			(hide yes)
			(effects
				(font
					(size 1.016 1.016)
					(thickness 0.1524)
				)
			)
		)
		(duplicate_pad_numbers_are_jumpers no)
		(fp_line
			(start 0.508 -0.9398)
			(end -0.508 -0.9398)
			(stroke
				(width 0.1524)
				(type default)
			)
			(layer "F.SilkS")
		)
		(fp_line
			(start -0.508 -0.9398)
			(end -0.508 0.9398)
			(stroke
				(width 0.1524)
				(type default)
			)
			(layer "F.SilkS")
		)
		(fp_rect
			(start -0.508 0.9398)
			(end 0.508 -0.9398)
			(stroke
				(width 0)
				(type default)
			)
			(fill no)
			(layer "F.CrtYd")
		)
		(fp_rect
			(start -0.508 0.9398)
			(end 0.508 -0.9398)
			(stroke
				(width 0)
				(type default)
			)
			(fill no)
			(layer "F.Fab")
		)
		(pad "1" smd custom
			(at 0 -0.4445 180)
			(size 0.1397 0.1397)
			(layers "F.Cu" "F.Mask" "F.Paste")
			(net "USB_EN_4")
			(options
				(clearance outline)
				(anchor circle)
			)
			(primitives
				(gr_poly
					(pts
						(arc
							(start -0.1778 -0.2794)
							(mid -0.249642 -0.249642)
							(end -0.2794 -0.1778)
						)
						(arc
							(start -0.2794 0.1778)
							(mid -0.249642 0.249642)
							(end -0.1778 0.2794)
						)
						(arc
							(start 0.1778 0.2794)
							(mid 0.249642 0.249642)
							(end 0.2794 0.1778)
						)
						(arc
							(start 0.2794 -0.1778)
							(mid 0.249642 -0.249642)
							(end 0.1778 -0.2794)
						)
					)
					(width 0)
					(fill yes)
				)
			)
		)
		(pad "2" smd custom
			(at 0 0.4445 180)
			(size 0.1397 0.1397)
			(layers "F.Cu" "F.Mask" "F.Paste")
			(net "GND")
			(options
				(clearance outline)
				(anchor circle)
			)
			(primitives
				(gr_poly
					(pts
						(arc
							(start -0.1778 -0.2794)
							(mid -0.249642 -0.249642)
							(end -0.2794 -0.1778)
						)
						(arc
							(start -0.2794 0.1778)
							(mid -0.249642 0.249642)
							(end -0.1778 0.2794)
						)
						(arc
							(start 0.1778 0.2794)
							(mid 0.249642 0.249642)
							(end 0.2794 0.1778)
						)
						(arc
							(start 0.2794 -0.1778)
							(mid 0.249642 -0.249642)
							(end 0.1778 -0.2794)
						)
					)
					(width 0)
					(fill yes)
				)
			)
		)
	)
	(footprint ""
		(layer "F.Cu")
		(at 152.4 -38.481)
		(property "Reference" "TP185"
			(at 0 0 0)
			(layer "F.SilkS")
			(hide yes)
			(effects
				(font
					(size 1.27 1.27)
				)
			)
		)
		(property "Value" "TPAD28-2-GP"
			(at -0.0127 -1.6637 0)
			(unlocked yes)
			(layer "F.Fab")
			(hide yes)
			(effects
				(font
					(size 1.016 1.016)
					(thickness 0.1524)
				)
			)
		)
		(property "Device Type" "TPAD28"
			(at -0.0127 -3.1877 0)
			(unlocked yes)
			(layer "F.Fab")
			(hide yes)
			(effects
				(font
					(size 1.016 1.016)
					(thickness 0.1524)
				)
			)
		)
		(duplicate_pad_numbers_are_jumpers no)
		(fp_poly
			(pts
				(arc
					(start 0.3556 0)
					(mid -0.3556 0)
					(end 0.3556 0)
				)
			)
			(stroke
				(width 0)
				(type default)
			)
			(fill no)
			(layer "F.CrtYd")
		)
		(fp_poly
			(pts
				(arc
					(start 0.6096 0)
					(mid -0.6096 0)
					(end 0.6096 0)
				)
			)
			(stroke
				(width 0)
				(type default)
			)
			(fill no)
			(layer "F.Fab")
		)
		(pad "1" smd circle
			(at 0 0)
			(size 0.7112 0.7112)
			(layers "F.Cu" "F.Mask" "F.Paste")
			(net "ZDEF_EXTB_TP_B2")
		)
	)
	(footprint ""
		(layer "F.Cu")
		(at 155.575 -136.6012 180)
		(property "Reference" "C213"
			(at 0 0 180)
			(layer "F.SilkS")
			(hide yes)
			(effects
				(font
					(size 1.27 1.27)
				)
			)
		)
		(property "Value" "SC1U16V3KX-5GP"
			(at 0 -2.8194 180)
			(unlocked yes)
			(layer "F.Fab")
			(hide yes)
			(effects
				(font
					(size 1.016 1.016)
					(thickness 0.1524)
				)
			)
		)
		(property "Device Type" "C603H36"
			(at 0 -4.3434 180)
			(unlocked yes)
			(layer "F.Fab")
			(hide yes)
			(effects
				(font
					(size 1.016 1.016)
					(thickness 0.1524)
				)
			)
		)
		(duplicate_pad_numbers_are_jumpers no)
		(fp_line
			(start 0.508 0)
			(end -0.508 0)
			(stroke
				(width 0.2032)
				(type default)
			)
			(layer "F.SilkS")
		)
		(fp_rect
			(start -0.5842 1.3335)
			(end 0.5842 -1.3335)
			(stroke
				(width 0)
				(type default)
			)
			(fill no)
			(layer "F.CrtYd")
		)
		(fp_rect
			(start -0.5842 1.3335)
			(end 0.5842 -1.3335)
			(stroke
				(width 0)
				(type default)
			)
			(fill no)
			(layer "F.Fab")
		)
		(pad "1" smd custom
			(at 0 -0.762 180)
			(size 0.2159 0.2159)
			(layers "F.Cu" "F.Mask" "F.Paste")
			(net "GND")
			(options
				(clearance outline)
				(anchor circle)
			)
			(primitives
				(gr_poly
					(pts
						(arc
							(start -0.3302 -0.4318)
							(mid -0.402042 -0.402042)
							(end -0.4318 -0.3302)
						)
						(arc
							(start -0.4318 0.3302)
							(mid -0.402042 0.402042)
							(end -0.3302 0.4318)
						)
						(arc
							(start 0.3302 0.4318)
							(mid 0.402042 0.402042)
							(end 0.4318 0.3302)
						)
						(arc
							(start 0.4318 -0.3302)
							(mid 0.402042 -0.402042)
							(end 0.3302 -0.4318)
						)
					)
					(width 0)
					(fill yes)
				)
			)
		)
		(pad "2" smd custom
			(at 0 0.762 180)
			(size 0.2159 0.2159)
			(layers "F.Cu" "F.Mask" "F.Paste")
			(net "P1V8_STBY_EN_R")
			(options
				(clearance outline)
				(anchor circle)
			)
			(primitives
				(gr_poly
					(pts
						(arc
							(start -0.3302 -0.4318)
							(mid -0.402042 -0.402042)
							(end -0.4318 -0.3302)
						)
						(arc
							(start -0.4318 0.3302)
							(mid -0.402042 0.402042)
							(end -0.3302 0.4318)
						)
						(arc
							(start 0.3302 0.4318)
							(mid 0.402042 0.402042)
							(end 0.4318 0.3302)
						)
						(arc
							(start 0.4318 -0.3302)
							(mid 0.402042 -0.402042)
							(end 0.3302 -0.4318)
						)
					)
					(width 0)
					(fill yes)
				)
			)
		)
	)
	(footprint ""
		(layer "F.Cu")
		(at 112.87379 -6.643878 -90)
		(property "Reference" "R460"
			(at 0 0 270)
			(layer "F.SilkS")
			(hide yes)
			(effects
				(font
					(size 1.27 1.27)
				)
			)
		)
		(property "Value" "0R2J-2-GP"
			(at 0.064008 -3.993896 270)
			(unlocked yes)
			(layer "F.Fab")
			(hide yes)
			(effects
				(font
					(size 1.016 1.016)
					(thickness 0.1524)
				)
			)
		)
		(property "Device Type" "R402H16"
			(at 0.064008 -5.517896 270)
			(unlocked yes)
			(layer "F.Fab")
			(hide yes)
			(effects
				(font
					(size 1.016 1.016)
					(thickness 0.1524)
				)
			)
		)
		(duplicate_pad_numbers_are_jumpers no)
		(fp_line
			(start -0.508 -0.9398)
			(end -0.508 0.9398)
			(stroke
				(width 0.1524)
				(type default)
			)
			(layer "F.SilkS")
		)
		(fp_line
			(start 0.508 -0.9398)
			(end -0.508 -0.9398)
			(stroke
				(width 0.1524)
				(type default)
			)
			(layer "F.SilkS")
		)
		(fp_rect
			(start -0.508 0.9398)
			(end 0.508 -0.9398)
			(stroke
				(width 0)
				(type default)
			)
			(fill no)
			(layer "F.CrtYd")
		)
		(fp_rect
			(start -0.508 0.9398)
			(end 0.508 -0.9398)
			(stroke
				(width 0)
				(type default)
			)
			(fill no)
			(layer "F.Fab")
		)
		(pad "1" smd custom
			(at 0 -0.4445 270)
			(size 0.1397 0.1397)
			(layers "F.Cu" "F.Mask" "F.Paste")
			(net "MB0_CM_ADR2_R")
			(options
				(clearance outline)
				(anchor circle)
			)
			(primitives
				(gr_poly
					(pts
						(arc
							(start -0.1778 -0.2794)
							(mid -0.249642 -0.249642)
							(end -0.2794 -0.1778)
						)
						(arc
							(start -0.2794 0.1778)
							(mid -0.249642 0.249642)
							(end -0.1778 0.2794)
						)
						(arc
							(start 0.1778 0.2794)
							(mid 0.249642 0.249642)
							(end 0.2794 0.1778)
						)
						(arc
							(start 0.2794 -0.1778)
							(mid 0.249642 -0.249642)
							(end 0.1778 -0.2794)
						)
					)
					(width 0)
					(fill yes)
				)
			)
		)
		(pad "2" smd custom
			(at 0 0.4445 270)
			(size 0.1397 0.1397)
			(layers "F.Cu" "F.Mask" "F.Paste")
			(net "AGND_CURRENT_MON")
			(options
				(clearance outline)
				(anchor circle)
			)
			(primitives
				(gr_poly
					(pts
						(arc
							(start -0.1778 -0.2794)
							(mid -0.249642 -0.249642)
							(end -0.2794 -0.1778)
						)
						(arc
							(start -0.2794 0.1778)
							(mid -0.249642 0.249642)
							(end -0.1778 0.2794)
						)
						(arc
							(start 0.1778 0.2794)
							(mid 0.249642 0.249642)
							(end 0.2794 0.1778)
						)
						(arc
							(start 0.2794 -0.1778)
							(mid 0.249642 -0.249642)
							(end 0.1778 -0.2794)
						)
					)
					(width 0)
					(fill yes)
				)
			)
		)
	)
	(footprint ""
		(layer "F.Cu")
		(at 83.029044 -132.72135 90)
		(property "Reference" "C485"
			(at 0 0 90)
			(layer "F.SilkS")
			(hide yes)
			(effects
				(font
					(size 1.27 1.27)
				)
			)
		)
		(property "Value" "SCD1U16V2KX-3GP"
			(at 1.1811 -2.7051 90)
			(unlocked yes)
			(layer "F.Fab")
			(hide yes)
			(effects
				(font
					(size 1.016 1.016)
					(thickness 0.1524)
				)
			)
		)
		(property "Device Type" "C402H22"
			(at 1.1811 -4.2291 90)
			(unlocked yes)
			(layer "F.Fab")
			(hide yes)
			(effects
				(font
					(size 1.016 1.016)
					(thickness 0.1524)
				)
			)
		)
		(duplicate_pad_numbers_are_jumpers no)
		(fp_rect
			(start -0.4318 0.9525)
			(end 0.4318 -0.9525)
			(stroke
				(width 0)
				(type default)
			)
			(fill no)
			(layer "F.CrtYd")
		)
		(fp_rect
			(start -0.4318 0.9525)
			(end 0.4318 -0.9525)
			(stroke
				(width 0)
				(type default)
			)
			(fill no)
			(layer "F.Fab")
		)
		(pad "1" smd custom
			(at 0 -0.4445 90)
			(size 0.1524 0.1524)
			(layers "F.Cu" "F.Mask" "F.Paste")
			(net "P3V3_STBY")
			(options
				(clearance outline)
				(anchor circle)
			)
			(primitives
				(gr_poly
					(pts
						(arc
							(start 0.3048 -0.2032)
							(mid 0.275042 -0.275042)
							(end 0.2032 -0.3048)
						)
						(arc
							(start -0.2032 -0.3048)
							(mid -0.275042 -0.275042)
							(end -0.3048 -0.2032)
						)
						(arc
							(start -0.3048 0.2032)
							(mid -0.275042 0.275042)
							(end -0.2032 0.3048)
						)
						(arc
							(start 0.2032 0.3048)
							(mid 0.275042 0.275042)
							(end 0.3048 0.2032)
						)
					)
					(width 0)
					(fill yes)
				)
			)
		)
		(pad "2" smd custom
			(at 0 0.4445 90)
			(size 0.1524 0.1524)
			(layers "F.Cu" "F.Mask" "F.Paste")
			(net "GND")
			(options
				(clearance outline)
				(anchor circle)
			)
			(primitives
				(gr_poly
					(pts
						(arc
							(start 0.3048 -0.2032)
							(mid 0.275042 -0.275042)
							(end 0.2032 -0.3048)
						)
						(arc
							(start -0.2032 -0.3048)
							(mid -0.275042 -0.275042)
							(end -0.3048 -0.2032)
						)
						(arc
							(start -0.3048 0.2032)
							(mid -0.275042 0.275042)
							(end -0.2032 0.3048)
						)
						(arc
							(start 0.2032 0.3048)
							(mid 0.275042 0.275042)
							(end 0.3048 0.2032)
						)
					)
					(width 0)
					(fill yes)
				)
			)
		)
	)
	(footprint ""
		(layer "F.Cu")
		(at 186.443112 -45.884084 180)
		(property "Reference" "R660"
			(at 0 0 180)
			(layer "F.SilkS")
			(hide yes)
			(effects
				(font
					(size 1.27 1.27)
				)
			)
		)
		(property "Value" "10KR2F-2-GP"
			(at 0.064008 -3.993896 180)
			(unlocked yes)
			(layer "F.Fab")
			(hide yes)
			(effects
				(font
					(size 1.016 1.016)
					(thickness 0.1524)
				)
			)
		)
		(property "Device Type" "R402H16"
			(at 0.064008 -5.517896 180)
			(unlocked yes)
			(layer "F.Fab")
			(hide yes)
			(effects
				(font
					(size 1.016 1.016)
					(thickness 0.1524)
				)
			)
		)
		(duplicate_pad_numbers_are_jumpers no)
		(fp_line
			(start 0.508 -0.9398)
			(end -0.508 -0.9398)
			(stroke
				(width 0.1524)
				(type default)
			)
			(layer "F.SilkS")
		)
		(fp_line
			(start -0.508 -0.9398)
			(end -0.508 0.9398)
			(stroke
				(width 0.1524)
				(type default)
			)
			(layer "F.SilkS")
		)
		(fp_rect
			(start -0.508 0.9398)
			(end 0.508 -0.9398)
			(stroke
				(width 0)
				(type default)
			)
			(fill no)
			(layer "F.CrtYd")
		)
		(fp_rect
			(start -0.508 0.9398)
			(end 0.508 -0.9398)
			(stroke
				(width 0)
				(type default)
			)
			(fill no)
			(layer "F.Fab")
		)
		(pad "1" smd custom
			(at 0 -0.4445 180)
			(size 0.1397 0.1397)
			(layers "F.Cu" "F.Mask" "F.Paste")
			(net "P1V8")
			(options
				(clearance outline)
				(anchor circle)
			)
			(primitives
				(gr_poly
					(pts
						(arc
							(start -0.1778 -0.2794)
							(mid -0.249642 -0.249642)
							(end -0.2794 -0.1778)
						)
						(arc
							(start -0.2794 0.1778)
							(mid -0.249642 0.249642)
							(end -0.1778 0.2794)
						)
						(arc
							(start 0.1778 0.2794)
							(mid 0.249642 0.249642)
							(end 0.2794 0.1778)
						)
						(arc
							(start 0.2794 -0.1778)
							(mid 0.249642 -0.249642)
							(end 0.1778 -0.2794)
						)
					)
					(width 0)
					(fill yes)
				)
			)
		)
		(pad "2" smd custom
			(at 0 0.4445 180)
			(size 0.1397 0.1397)
			(layers "F.Cu" "F.Mask" "F.Paste")
			(net "XM_ADDR_0")
			(options
				(clearance outline)
				(anchor circle)
			)
			(primitives
				(gr_poly
					(pts
						(arc
							(start -0.1778 -0.2794)
							(mid -0.249642 -0.249642)
							(end -0.2794 -0.1778)
						)
						(arc
							(start -0.2794 0.1778)
							(mid -0.249642 0.249642)
							(end -0.1778 0.2794)
						)
						(arc
							(start 0.1778 0.2794)
							(mid 0.249642 0.249642)
							(end 0.2794 0.1778)
						)
						(arc
							(start 0.2794 -0.1778)
							(mid 0.249642 -0.249642)
							(end 0.1778 -0.2794)
						)
					)
					(width 0)
					(fill yes)
				)
			)
		)
	)
	(footprint ""
		(layer "F.Cu")
		(at 39.712646 -174.67961 -90)
		(property "Reference" "R489"
			(at 0 0 270)
			(layer "F.SilkS")
			(hide yes)
			(effects
				(font
					(size 1.27 1.27)
				)
			)
		)
		(property "Value" "10R3F-GP"
			(at -0.0254 -2.5146 270)
			(unlocked yes)
			(layer "F.Fab")
			(hide yes)
			(effects
				(font
					(size 1.016 1.016)
					(thickness 0.1524)
				)
			)
		)
		(property "Device Type" "R603H22"
			(at -0.0254 -4.0386 270)
			(unlocked yes)
			(layer "F.Fab")
			(hide yes)
			(effects
				(font
					(size 1.016 1.016)
					(thickness 0.1524)
				)
			)
		)
		(duplicate_pad_numbers_are_jumpers no)
		(fp_line
			(start -0.4826 0)
			(end -0.2032 0)
			(stroke
				(width 0.2032)
				(type default)
			)
			(layer "F.SilkS")
		)
		(fp_line
			(start 0.2032 0)
			(end 0.4826 0)
			(stroke
				(width 0.2032)
				(type default)
			)
			(layer "F.SilkS")
		)
		(fp_rect
			(start -0.5842 1.3335)
			(end 0.5842 -1.3335)
			(stroke
				(width 0)
				(type default)
			)
			(fill no)
			(layer "F.CrtYd")
		)
		(fp_rect
			(start -0.5842 1.3335)
			(end 0.5842 -1.3335)
			(stroke
				(width 0)
				(type default)
			)
			(fill no)
			(layer "F.Fab")
		)
		(pad "1" smd custom
			(at 0 -0.762 270)
			(size 0.2159 0.2159)
			(layers "F.Cu" "F.Mask" "F.Paste")
			(net "P3V3_STBY_OUT")
			(options
				(clearance outline)
				(anchor circle)
			)
			(primitives
				(gr_poly
					(pts
						(arc
							(start -0.3302 -0.4318)
							(mid -0.402042 -0.402042)
							(end -0.4318 -0.3302)
						)
						(arc
							(start -0.4318 0.3302)
							(mid -0.402042 0.402042)
							(end -0.3302 0.4318)
						)
						(arc
							(start 0.3302 0.4318)
							(mid 0.402042 0.402042)
							(end 0.4318 0.3302)
						)
						(arc
							(start 0.4318 -0.3302)
							(mid 0.402042 -0.402042)
							(end 0.3302 -0.4318)
						)
					)
					(width 0)
					(fill yes)
				)
			)
		)
		(pad "2" smd custom
			(at 0 0.762 270)
			(size 0.2159 0.2159)
			(layers "F.Cu" "F.Mask" "F.Paste")
			(net "P3V3_STBY_VFB_R")
			(options
				(clearance outline)
				(anchor circle)
			)
			(primitives
				(gr_poly
					(pts
						(arc
							(start -0.3302 -0.4318)
							(mid -0.402042 -0.402042)
							(end -0.4318 -0.3302)
						)
						(arc
							(start -0.4318 0.3302)
							(mid -0.402042 0.402042)
							(end -0.3302 0.4318)
						)
						(arc
							(start 0.3302 0.4318)
							(mid 0.402042 0.402042)
							(end 0.4318 0.3302)
						)
						(arc
							(start 0.4318 -0.3302)
							(mid 0.402042 -0.402042)
							(end 0.3302 -0.4318)
						)
					)
					(width 0)
					(fill yes)
				)
			)
		)
	)
)
